(kicad_pcb
	(version 20260206)
	(generator "pcbnew")
	(generator_version "10.0")
	(general
		(thickness 1.6)
		(legacy_teardrops no)
	)
	(paper "A4")
	(title_block
		(title "01162023_DA0F0TEBIF0_F0T_Expander_BD_F_brd_V02_OCP.brd")
		(comment 1 "Grand Teton / footprints 296-301 of 9728")
	)
	(layers
		(0 "F.Cu" signal "TOP")
		(4 "In1.Cu" signal "GND")
		(6 "In2.Cu" signal "VCC")
		(8 "In3.Cu" signal "VCC1")
		(10 "In4.Cu" signal "GND1")
		(12 "In5.Cu" signal "IN1")
		(14 "In6.Cu" signal "GND2")
		(16 "In7.Cu" signal "IN2")
		(18 "In8.Cu" signal "GND3")
		(20 "In9.Cu" signal "IN3")
		(22 "In10.Cu" signal "GND4")
		(24 "In11.Cu" signal "IN4")
		(26 "In12.Cu" signal "GND5")
		(28 "In13.Cu" signal "IN5")
		(30 "In14.Cu" signal "GND6")
		(32 "In15.Cu" signal "IN6")
		(34 "In16.Cu" signal "GND7")
		(2 "B.Cu" signal "BOTTOM")
		(9 "F.Adhes" user "F.Adhesive")
		(11 "B.Adhes" user "B.Adhesive")
		(13 "F.Paste" user "Package Geometry/Pastemask Top")
		(15 "B.Paste" user "Package Geometry/Pastemask Bottom")
		(5 "F.SilkS" user "Ref Des/Silkscreen Top")
		(7 "B.SilkS" user "Ref Des/Silkscreen Bottom")
		(1 "F.Mask" user "Board Geometry/Soldermask Top")
		(3 "B.Mask" user "Board Geometry/Soldermask Bottom")
		(17 "Dwgs.User" user "User.Drawings")
		(19 "Cmts.User" user "User.Comments")
		(21 "Eco1.User" user "User.Eco1")
		(23 "Eco2.User" user "User.Eco2")
		(25 "Edge.Cuts" user "Board Geometry/Outline")
		(27 "Margin" user)
		(31 "F.CrtYd" user "Package Geometry/Place Bound Top")
		(29 "B.CrtYd" user "Package Geometry/Place Bound Bottom")
		(35 "F.Fab" user "Ref Des/Assembly Top")
		(33 "B.Fab" user "Ref Des/Assembly Bottom")
	)
	(footprint ""
		(layer "F.Cu")
		(at 242.110768 8.076692 180)
		(property "Reference" "DE11T_1"
			(at 2.614168 3.147822 0)
			(unlocked yes)
			(layer "F.SilkS")
			(effects
				(font
					(size 0.7874 0.5842)
					(thickness 0.1524)
				)
				(justify left)
			)
		)
		(property "Value" ""
			(at 0 0 180)
			(layer "F.Fab")
			(effects
				(font
					(size 1.27 1.27)
				)
			)
		)
		(duplicate_pad_numbers_are_jumpers no)
		(fp_line
			(start 1.2192 2.1082)
			(end -1.2192 2.1082)
			(stroke
				(width 0.1524)
				(type default)
			)
			(layer "F.SilkS")
		)
		(fp_line
			(start 1.2192 -2.1082)
			(end 1.2192 2.1082)
			(stroke
				(width 0.1524)
				(type default)
			)
			(layer "F.SilkS")
		)
		(fp_line
			(start -1.2192 2.1082)
			(end -1.2192 -2.1082)
			(stroke
				(width 0.1524)
				(type default)
			)
			(layer "F.SilkS")
		)
		(fp_line
			(start -1.2192 -2.1082)
			(end 1.2192 -2.1082)
			(stroke
				(width 0.1524)
				(type default)
			)
			(layer "F.SilkS")
		)
		(pad "" np_thru_hole circle
			(at -2.8829 -1.27 90)
			(size 1.0414 1.0414)
			(drill 1.0414)
			(layers "*.Cu" "*.Mask")
			(clearance 0.381)
			(thermal_gap 0.381)
		)
		(pad "" np_thru_hole circle
			(at -2.8829 1.27 90)
			(size 1.0414 1.0414)
			(drill 1.0414)
			(layers "*.Cu" "*.Mask")
			(clearance 0.381)
			(thermal_gap 0.381)
		)
		(pad "" np_thru_hole circle
			(at 3.4671 -1.27 90)
			(size 1.0414 1.0414)
			(drill 1.0414)
			(layers "*.Cu" "*.Mask")
			(clearance 0.381)
			(thermal_gap 0.381)
		)
		(pad "" np_thru_hole circle
			(at 3.4671 1.27 90)
			(size 1.0414 1.0414)
			(drill 1.0414)
			(layers "*.Cu" "*.Mask")
			(clearance 0.381)
			(thermal_gap 0.381)
		)
		(pad "1" smd rect
			(at 0.8255 -0.249936 90)
			(size 0.3048 0.508)
			(layers "F.Cu" "F.Mask" "F.Paste")
			(net "85_10INCH_TOP_DN")
		)
		(pad "2" smd rect
			(at 0.8255 0.249936 90)
			(size 0.3048 0.508)
			(layers "F.Cu" "F.Mask" "F.Paste")
			(net "85_10INCH_TOP_DP")
		)
		(pad "3" smd circle
			(at 0 0 180)
			(size 0 0)
			(layers "F.Cu" "F.Mask" "F.Paste")
			(net "COUPON_GND2")
		)
		(zone
			(layer "F.Cu")
			(hatch none 0.5)
			(connect_pads
				(clearance 0)
			)
			(min_thickness 0.25)
			(keepout
				(tracks not_allowed)
				(vias allowed)
				(pads allowed)
				(copperpour not_allowed)
				(footprints allowed)
			)
			(placement
				(enabled no)
				(sheetname "")
			)
			(fill
				(thermal_gap 0.5)
				(thermal_bridge_width 0.5)
				(island_removal_mode 0)
			)
			(polygon
				(pts
					(xy 240.993168 8.625332) (xy 240.993168 8.529828) (xy 241.590068 8.529828) (xy 241.590068 8.123428)
					(xy 240.993168 8.123428) (xy 240.993168 8.029956) (xy 241.590068 8.029956) (xy 241.590068 7.623556)
					(xy 240.993168 7.623556) (xy 240.993168 7.528052) (xy 241.691668 7.528052) (xy 241.691668 8.625332)
				)
			)
		)
		(zone
			(layers "F.Cu" "B.Cu" "In1.Cu" "In2.Cu" "In3.Cu" "In4.Cu" "In5.Cu" "In6.Cu"
				"In7.Cu" "In8.Cu" "In9.Cu" "In10.Cu" "In11.Cu" "In12.Cu" "In13.Cu" "In14.Cu"
				"In15.Cu" "In16.Cu"
			)
			(hatch none 0.5)
			(connect_pads
				(clearance 0)
			)
			(min_thickness 0.25)
			(keepout
				(tracks not_allowed)
				(vias allowed)
				(pads allowed)
				(copperpour not_allowed)
				(footprints allowed)
			)
			(placement
				(enabled no)
				(sheetname "")
			)
			(fill
				(thermal_gap 0.5)
				(thermal_bridge_width 0.5)
				(island_removal_mode 0)
			)
			(polygon
				(pts
					(arc
						(start 239.570768 6.806692)
						(mid 237.716568 6.806692)
						(end 239.570768 6.806692)
					)
				)
			)
		)
		(zone
			(layers "F.Cu" "B.Cu" "In1.Cu" "In2.Cu" "In3.Cu" "In4.Cu" "In5.Cu" "In6.Cu"
				"In7.Cu" "In8.Cu" "In9.Cu" "In10.Cu" "In11.Cu" "In12.Cu" "In13.Cu" "In14.Cu"
				"In15.Cu" "In16.Cu"
			)
			(hatch none 0.5)
			(connect_pads
				(clearance 0)
			)
			(min_thickness 0.25)
			(keepout
				(tracks not_allowed)
				(vias allowed)
				(pads allowed)
				(copperpour not_allowed)
				(footprints allowed)
			)
			(placement
				(enabled no)
				(sheetname "")
			)
			(fill
				(thermal_gap 0.5)
				(thermal_bridge_width 0.5)
				(island_removal_mode 0)
			)
			(polygon
				(pts
					(arc
						(start 239.570768 9.346692)
						(mid 237.716568 9.346692)
						(end 239.570768 9.346692)
					)
				)
			)
		)
		(zone
			(layers "F.Cu" "B.Cu" "In1.Cu" "In2.Cu" "In3.Cu" "In4.Cu" "In5.Cu" "In6.Cu"
				"In7.Cu" "In8.Cu" "In9.Cu" "In10.Cu" "In11.Cu" "In12.Cu" "In13.Cu" "In14.Cu"
				"In15.Cu" "In16.Cu"
			)
			(hatch none 0.5)
			(connect_pads
				(clearance 0)
			)
			(min_thickness 0.25)
			(keepout
				(tracks not_allowed)
				(vias allowed)
				(pads allowed)
				(copperpour not_allowed)
				(footprints allowed)
			)
			(placement
				(enabled no)
				(sheetname "")
			)
			(fill
				(thermal_gap 0.5)
				(thermal_bridge_width 0.5)
				(island_removal_mode 0)
			)
			(polygon
				(pts
					(arc
						(start 245.920768 6.806692)
						(mid 244.066568 6.806692)
						(end 245.920768 6.806692)
					)
				)
			)
		)
		(zone
			(layers "F.Cu" "B.Cu" "In1.Cu" "In2.Cu" "In3.Cu" "In4.Cu" "In5.Cu" "In6.Cu"
				"In7.Cu" "In8.Cu" "In9.Cu" "In10.Cu" "In11.Cu" "In12.Cu" "In13.Cu" "In14.Cu"
				"In15.Cu" "In16.Cu"
			)
			(hatch none 0.5)
			(connect_pads
				(clearance 0)
			)
			(min_thickness 0.25)
			(keepout
				(tracks not_allowed)
				(vias allowed)
				(pads allowed)
				(copperpour not_allowed)
				(footprints allowed)
			)
			(placement
				(enabled no)
				(sheetname "")
			)
			(fill
				(thermal_gap 0.5)
				(thermal_bridge_width 0.5)
				(island_removal_mode 0)
			)
			(polygon
				(pts
					(arc
						(start 245.920768 9.346692)
						(mid 244.066568 9.346692)
						(end 245.920768 9.346692)
					)
				)
			)
		)
	)
	(footprint ""
		(layer "F.Cu")
		(at 1.66624 -393.474194 90)
		(property "Reference" "C4475"
			(at 0 0 90)
			(layer "F.SilkS")
			(hide yes)
			(effects
				(font
					(size 1.27 1.27)
				)
			)
		)
		(property "Value" ""
			(at 0 0 90)
			(layer "F.Fab")
			(effects
				(font
					(size 1.27 1.27)
				)
			)
		)
		(duplicate_pad_numbers_are_jumpers no)
		(fp_line
			(start 0.7874 -0.4064)
			(end 0.7874 0.4064)
			(stroke
				(width 0.1524)
				(type default)
			)
			(layer "F.SilkS")
		)
		(fp_line
			(start -0.7874 -0.4064)
			(end 0.7874 -0.4064)
			(stroke
				(width 0.1524)
				(type default)
			)
			(layer "F.SilkS")
		)
		(fp_line
			(start 0.7874 0.4064)
			(end -0.7874 0.4064)
			(stroke
				(width 0.1524)
				(type default)
			)
			(layer "F.SilkS")
		)
		(fp_line
			(start -0.7874 0.4064)
			(end -0.7874 -0.4064)
			(stroke
				(width 0.1524)
				(type default)
			)
			(layer "F.SilkS")
		)
		(fp_line
			(start -0.12065 -0.305054)
			(end -0.12065 -0.2794)
			(stroke
				(width 0.1)
				(type default)
			)
			(layer "F.Fab")
		)
		(fp_line
			(start -0.67945 -0.305054)
			(end -0.12065 -0.305054)
			(stroke
				(width 0.1)
				(type default)
			)
			(layer "F.Fab")
		)
		(fp_line
			(start 0.67945 -0.3048)
			(end 0.67945 0.3048)
			(stroke
				(width 0.1)
				(type default)
			)
			(layer "F.Fab")
		)
		(fp_line
			(start 0.12065 -0.3048)
			(end 0.67945 -0.3048)
			(stroke
				(width 0.1)
				(type default)
			)
			(layer "F.Fab")
		)
		(fp_line
			(start 0.12065 -0.2794)
			(end 0.12065 -0.3048)
			(stroke
				(width 0.1)
				(type default)
			)
			(layer "F.Fab")
		)
		(fp_line
			(start -0.12065 -0.2794)
			(end 0.12065 -0.2794)
			(stroke
				(width 0.1)
				(type default)
			)
			(layer "F.Fab")
		)
		(fp_line
			(start 0.120396 0.2794)
			(end -0.12065 0.2794)
			(stroke
				(width 0.1)
				(type default)
			)
			(layer "F.Fab")
		)
		(fp_line
			(start -0.12065 0.2794)
			(end -0.12065 0.3048)
			(stroke
				(width 0.1)
				(type default)
			)
			(layer "F.Fab")
		)
		(fp_line
			(start 0.67945 0.3048)
			(end 0.120396 0.3048)
			(stroke
				(width 0.1)
				(type default)
			)
			(layer "F.Fab")
		)
		(fp_line
			(start 0.120396 0.3048)
			(end 0.120396 0.2794)
			(stroke
				(width 0.1)
				(type default)
			)
			(layer "F.Fab")
		)
		(fp_line
			(start -0.12065 0.3048)
			(end -0.67945 0.3048)
			(stroke
				(width 0.1)
				(type default)
			)
			(layer "F.Fab")
		)
		(fp_line
			(start -0.67945 0.3048)
			(end -0.67945 -0.305054)
			(stroke
				(width 0.1)
				(type default)
			)
			(layer "F.Fab")
		)
		(pad "1" smd circle
			(at -0.40005 0 90)
			(size 0 0)
			(layers "F.Cu" "F.Mask" "F.Paste")
			(net "BIC_USB_8042_HUB_GRSTZ")
		)
		(pad "2" smd circle
			(at 0.40005 0 90)
			(size 0 0)
			(layers "F.Cu" "F.Mask" "F.Paste")
			(net "GND")
		)
	)
	(footprint ""
		(layer "F.Cu")
		(at 270.980662 -356.244906 90)
		(property "Reference" "C609"
			(at 0 0 90)
			(layer "F.SilkS")
			(hide yes)
			(effects
				(font
					(size 1.27 1.27)
				)
			)
		)
		(property "Value" ""
			(at 0 0 90)
			(layer "F.Fab")
			(effects
				(font
					(size 1.27 1.27)
				)
			)
		)
		(duplicate_pad_numbers_are_jumpers no)
		(fp_line
			(start 0.299974 -0.150114)
			(end 0.299974 0.150114)
			(stroke
				(width 0.1)
				(type default)
			)
			(layer "F.Fab")
		)
		(fp_line
			(start -0.299974 -0.150114)
			(end 0.299974 -0.150114)
			(stroke
				(width 0.1)
				(type default)
			)
			(layer "F.Fab")
		)
		(fp_line
			(start 0.299974 0.150114)
			(end -0.299974 0.150114)
			(stroke
				(width 0.1)
				(type default)
			)
			(layer "F.Fab")
		)
		(fp_line
			(start -0.299974 0.150114)
			(end -0.299974 -0.150114)
			(stroke
				(width 0.1)
				(type default)
			)
			(layer "F.Fab")
		)
		(pad "1" smd rect
			(at -0.2667 0 90)
			(size 0.3048 0.381)
			(layers "F.Cu" "F.Mask" "F.Paste")
			(net "P5E_PEX2_STN7_TX_DP<114>")
		)
		(pad "2" smd rect
			(at 0.2667 0 90)
			(size 0.3048 0.381)
			(layers "F.Cu" "F.Mask" "F.Paste")
			(net "P5E_PEX2_STN7_TX_C_DP<114>")
		)
	)
	(footprint ""
		(layer "F.Cu")
		(at 99.97948 -384.777742 -90)
		(property "Reference" "R6728"
			(at 0 0 270)
			(layer "F.SilkS")
			(hide yes)
			(effects
				(font
					(size 1.27 1.27)
				)
			)
		)
		(property "Value" ""
			(at 0 0 270)
			(layer "F.Fab")
			(effects
				(font
					(size 1.27 1.27)
				)
			)
		)
		(duplicate_pad_numbers_are_jumpers no)
		(fp_line
			(start -0.7874 0.4064)
			(end -0.7874 -0.4064)
			(stroke
				(width 0.1524)
				(type default)
			)
			(layer "F.SilkS")
		)
		(fp_line
			(start 0.7874 0.4064)
			(end -0.7874 0.4064)
			(stroke
				(width 0.1524)
				(type default)
			)
			(layer "F.SilkS")
		)
		(fp_line
			(start 0.008636 -0.4064)
			(end 0.7874 -0.4064)
			(stroke
				(width 0.1524)
				(type default)
			)
			(layer "F.SilkS")
		)
		(fp_line
			(start -0.67945 0.3048)
			(end -0.67945 -0.305054)
			(stroke
				(width 0.1)
				(type default)
			)
			(layer "F.Fab")
		)
		(fp_line
			(start -0.12065 0.3048)
			(end -0.67945 0.3048)
			(stroke
				(width 0.1)
				(type default)
			)
			(layer "F.Fab")
		)
		(fp_line
			(start 0.120396 0.3048)
			(end 0.120396 0.2794)
			(stroke
				(width 0.1)
				(type default)
			)
			(layer "F.Fab")
		)
		(fp_line
			(start 0.67945 0.3048)
			(end 0.120396 0.3048)
			(stroke
				(width 0.1)
				(type default)
			)
			(layer "F.Fab")
		)
		(fp_line
			(start -0.12065 0.2794)
			(end -0.12065 0.3048)
			(stroke
				(width 0.1)
				(type default)
			)
			(layer "F.Fab")
		)
		(fp_line
			(start 0.120396 0.2794)
			(end -0.12065 0.2794)
			(stroke
				(width 0.1)
				(type default)
			)
			(layer "F.Fab")
		)
		(fp_line
			(start -0.12065 -0.2794)
			(end 0.12065 -0.2794)
			(stroke
				(width 0.1)
				(type default)
			)
			(layer "F.Fab")
		)
		(fp_line
			(start 0.12065 -0.2794)
			(end 0.12065 -0.3048)
			(stroke
				(width 0.1)
				(type default)
			)
			(layer "F.Fab")
		)
		(fp_line
			(start 0.12065 -0.3048)
			(end 0.67945 -0.3048)
			(stroke
				(width 0.1)
				(type default)
			)
			(layer "F.Fab")
		)
		(fp_line
			(start 0.67945 -0.3048)
			(end 0.67945 0.3048)
			(stroke
				(width 0.1)
				(type default)
			)
			(layer "F.Fab")
		)
		(fp_line
			(start -0.67945 -0.305054)
			(end -0.12065 -0.305054)
			(stroke
				(width 0.1)
				(type default)
			)
			(layer "F.Fab")
		)
		(fp_line
			(start -0.12065 -0.305054)
			(end -0.12065 -0.2794)
			(stroke
				(width 0.1)
				(type default)
			)
			(layer "F.Fab")
		)
		(pad "1" smd rect
			(at -0.40005 0 90)
			(size 0.4572 0.508)
			(layers "F.Cu" "F.Mask" "F.Paste")
			(net "USB2_MB_BMC_DN")
		)
		(pad "2" smd rect
			(at 0.40005 0 90)
			(size 0.4572 0.508)
			(layers "F.Cu" "F.Mask" "F.Paste")
			(net "USB2_MB_BMC_USB8042_DN")
		)
	)
	(footprint ""
		(layer "F.Cu")
		(at 175.0949 -96.702372 180)
		(property "Reference" "R200"
			(at 0 0 180)
			(layer "F.SilkS")
			(hide yes)
			(effects
				(font
					(size 1.27 1.27)
				)
			)
		)
		(property "Value" ""
			(at 0 0 180)
			(layer "F.Fab")
			(effects
				(font
					(size 1.27 1.27)
				)
			)
		)
		(duplicate_pad_numbers_are_jumpers no)
		(fp_line
			(start 0.7874 0.4064)
			(end -0.7874 0.4064)
			(stroke
				(width 0.1524)
				(type default)
			)
			(layer "F.SilkS")
		)
		(fp_line
			(start 0.7874 -0.4064)
			(end 0.7874 0.4064)
			(stroke
				(width 0.1524)
				(type default)
			)
			(layer "F.SilkS")
		)
		(fp_line
			(start -0.7874 0.4064)
			(end -0.7874 -0.4064)
			(stroke
				(width 0.1524)
				(type default)
			)
			(layer "F.SilkS")
		)
		(fp_line
			(start -0.7874 -0.4064)
			(end 0.7874 -0.4064)
			(stroke
				(width 0.1524)
				(type default)
			)
			(layer "F.SilkS")
		)
		(fp_line
			(start 0.67945 0.3048)
			(end 0.120396 0.3048)
			(stroke
				(width 0.1)
				(type default)
			)
			(layer "F.Fab")
		)
		(fp_line
			(start 0.67945 -0.3048)
			(end 0.67945 0.3048)
			(stroke
				(width 0.1)
				(type default)
			)
			(layer "F.Fab")
		)
		(fp_line
			(start 0.12065 -0.2794)
			(end 0.12065 -0.3048)
			(stroke
				(width 0.1)
				(type default)
			)
			(layer "F.Fab")
		)
		(fp_line
			(start 0.12065 -0.3048)
			(end 0.67945 -0.3048)
			(stroke
				(width 0.1)
				(type default)
			)
			(layer "F.Fab")
		)
		(fp_line
			(start 0.120396 0.3048)
			(end 0.120396 0.2794)
			(stroke
				(width 0.1)
				(type default)
			)
			(layer "F.Fab")
		)
		(fp_line
			(start 0.120396 0.2794)
			(end -0.12065 0.2794)
			(stroke
				(width 0.1)
				(type default)
			)
			(layer "F.Fab")
		)
		(fp_line
			(start -0.12065 0.3048)
			(end -0.67945 0.3048)
			(stroke
				(width 0.1)
				(type default)
			)
			(layer "F.Fab")
		)
		(fp_line
			(start -0.12065 0.2794)
			(end -0.12065 0.3048)
			(stroke
				(width 0.1)
				(type default)
			)
			(layer "F.Fab")
		)
		(fp_line
			(start -0.12065 -0.2794)
			(end 0.12065 -0.2794)
			(stroke
				(width 0.1)
				(type default)
			)
			(layer "F.Fab")
		)
		(fp_line
			(start -0.12065 -0.305054)
			(end -0.12065 -0.2794)
			(stroke
				(width 0.1)
				(type default)
			)
			(layer "F.Fab")
		)
		(fp_line
			(start -0.67945 0.3048)
			(end -0.67945 -0.305054)
			(stroke
				(width 0.1)
				(type default)
			)
			(layer "F.Fab")
		)
		(fp_line
			(start -0.67945 -0.305054)
			(end -0.12065 -0.305054)
			(stroke
				(width 0.1)
				(type default)
			)
			(layer "F.Fab")
		)
		(pad "1" smd circle
			(at -0.40005 0 180)
			(size 0 0)
			(layers "F.Cu" "F.Mask" "F.Paste")
			(net "RST_NIC3_PERST2_R_N")
		)
		(pad "2" smd circle
			(at 0.40005 0 180)
			(size 0 0)
			(layers "F.Cu" "F.Mask" "F.Paste")
			(net "RST_HP_NIC3_BUF_N")
		)
	)
	(footprint ""
		(layer "F.Cu")
		(at 140.074142 -177.929286 180)
		(property "Reference" "R1102"
			(at 0 0 180)
			(layer "F.SilkS")
			(hide yes)
			(effects
				(font
					(size 1.27 1.27)
				)
			)
		)
		(property "Value" ""
			(at 0 0 180)
			(layer "F.Fab")
			(effects
				(font
					(size 1.27 1.27)
				)
			)
		)
		(duplicate_pad_numbers_are_jumpers no)
		(fp_line
			(start -0.7874 -0.4064)
			(end 0.7874 -0.4064)
			(stroke
				(width 0.1524)
				(type default)
			)
			(layer "F.SilkS")
		)
		(fp_line
			(start 0.67945 0.3048)
			(end 0.120396 0.3048)
			(stroke
				(width 0.1)
				(type default)
			)
			(layer "F.Fab")
		)
		(fp_line
			(start 0.67945 -0.3048)
			(end 0.67945 0.3048)
			(stroke
				(width 0.1)
				(type default)
			)
			(layer "F.Fab")
		)
		(fp_line
			(start 0.12065 -0.2794)
			(end 0.12065 -0.3048)
			(stroke
				(width 0.1)
				(type default)
			)
			(layer "F.Fab")
		)
		(fp_line
			(start 0.12065 -0.3048)
			(end 0.67945 -0.3048)
			(stroke
				(width 0.1)
				(type default)
			)
			(layer "F.Fab")
		)
		(fp_line
			(start 0.120396 0.3048)
			(end 0.120396 0.2794)
			(stroke
				(width 0.1)
				(type default)
			)
			(layer "F.Fab")
		)
		(fp_line
			(start 0.120396 0.2794)
			(end -0.12065 0.2794)
			(stroke
				(width 0.1)
				(type default)
			)
			(layer "F.Fab")
		)
		(fp_line
			(start -0.12065 0.3048)
			(end -0.67945 0.3048)
			(stroke
				(width 0.1)
				(type default)
			)
			(layer "F.Fab")
		)
		(fp_line
			(start -0.12065 0.2794)
			(end -0.12065 0.3048)
			(stroke
				(width 0.1)
				(type default)
			)
			(layer "F.Fab")
		)
		(fp_line
			(start -0.12065 -0.2794)
			(end 0.12065 -0.2794)
			(stroke
				(width 0.1)
				(type default)
			)
			(layer "F.Fab")
		)
		(fp_line
			(start -0.12065 -0.305054)
			(end -0.12065 -0.2794)
			(stroke
				(width 0.1)
				(type default)
			)
			(layer "F.Fab")
		)
		(fp_line
			(start -0.67945 0.3048)
			(end -0.67945 -0.305054)
			(stroke
				(width 0.1)
				(type default)
			)
			(layer "F.Fab")
		)
		(fp_line
			(start -0.67945 -0.305054)
			(end -0.12065 -0.305054)
			(stroke
				(width 0.1)
				(type default)
			)
			(layer "F.Fab")
		)
		(pad "1" smd circle
			(at -0.40005 0 180)
			(size 0 0)
			(layers "F.Cu" "F.Mask" "F.Paste")
			(net "CLK_100M_DB2000QL_NIC4_R_DP")
		)
		(pad "2" smd circle
			(at 0.40005 0 180)
			(size 0 0)
			(layers "F.Cu" "F.Mask" "F.Paste")
			(net "CLK_100M_DB2000QL_NIC4_DP")
		)
	)
)
